# SCM (Grand Teton) — schematic netlist excerpt (pin names and nets, part order shuffled) for the footprints in the layout excerpt that follows; sources: Cadence DE-HDL packaged netlist, KiCad conversion of 12092022_DA0F0TMDCD0_F0T_Management_Board_D_brd_V3_OCP.brd

C231  Q_CAP  0.1UF 25V 10% X7R  pkg 0402  page 31 : A = P3V3_AUX ; B = GND
C140  Q_CAP  0.1UF 25V 10% X7R  pkg 0402  page 17 : A = P1V2_P1V0_I3C_VDDL2 ; B = GND

(kicad_pcb
	(version 20260206)
	(generator "pcbnew")
	(generator_version "10.0")
	(general
		(thickness 1.6)
		(legacy_teardrops no)
	)
	(paper "A4")
	(title_block
		(title "12092022_DA0F0TMDCD0_F0T_Management_Board_D_brd_V3_OCP.brd")
		(comment 1 "Grand Teton / footprints 1328-1329 of 1440")
	)
	(layers
		(0 "F.Cu" signal "TOP")
		(4 "In1.Cu" signal "GND")
		(6 "In2.Cu" signal "IN1")
		(8 "In3.Cu" signal "GND1")
		(10 "In4.Cu" signal "IN2")
		(12 "In5.Cu" signal "VCC")
		(14 "In6.Cu" signal "VCC1")
		(16 "In7.Cu" signal "IN3")
		(18 "In8.Cu" signal "GND2")
		(20 "In9.Cu" signal "IN4")
		(22 "In10.Cu" signal "GND3")
		(2 "B.Cu" signal "BOTTOM")
		(9 "F.Adhes" user "F.Adhesive")
		(11 "B.Adhes" user "B.Adhesive")
		(13 "F.Paste" user "Package Geometry/Pastemask Top")
		(15 "B.Paste" user "Package Geometry/Pastemask Bottom")
		(5 "F.SilkS" user "Ref Des/Silkscreen Top")
		(7 "B.SilkS" user "Ref Des/Silkscreen Bottom")
		(1 "F.Mask" user "Board Geometry/Soldermask Top")
		(3 "B.Mask" user "Board Geometry/Soldermask Bottom")
		(17 "Dwgs.User" user "User.Drawings")
		(19 "Cmts.User" user "User.Comments")
		(21 "Eco1.User" user "User.Eco1")
		(23 "Eco2.User" user "User.Eco2")
		(25 "Edge.Cuts" user "Board Geometry/Outline")
		(27 "Margin" user)
		(31 "F.CrtYd" user "Package Geometry/Place Bound Top")
		(29 "B.CrtYd" user "Package Geometry/Place Bound Bottom")
		(35 "F.Fab" user "Ref Des/Assembly Top")
		(33 "B.Fab" user "Ref Des/Assembly Bottom")
	)
	(footprint ""
		(layer "B.Cu")
		(at 49.5046 -52.3748 180)
		(property "Reference" "C140"
			(at 0 0 0)
			(layer "B.SilkS")
			(hide yes)
			(effects
				(font
					(size 1.27 1.27)
				)
				(justify mirror)
			)
		)
		(property "Value" ""
			(at 0 0 0)
			(layer "B.Fab")
			(effects
				(font
					(size 1.27 1.27)
				)
				(justify mirror)
			)
		)
		(duplicate_pad_numbers_are_jumpers no)
		(fp_line
			(start 0.7874 0.4064)
			(end 0.7874 -0.4064)
			(stroke
				(width 0.1524)
				(type default)
			)
			(layer "B.SilkS")
		)
		(fp_line
			(start 0.7874 -0.4064)
			(end -0.7874 -0.4064)
			(stroke
				(width 0.1524)
				(type default)
			)
			(layer "B.SilkS")
		)
		(fp_line
			(start -0.7874 0.4064)
			(end 0.7874 0.4064)
			(stroke
				(width 0.1524)
				(type default)
			)
			(layer "B.SilkS")
		)
		(fp_line
			(start -0.7874 -0.4064)
			(end -0.7874 0.4064)
			(stroke
				(width 0.1524)
				(type default)
			)
			(layer "B.SilkS")
		)
		(fp_line
			(start 0.67945 0.3048)
			(end 0.67945 -0.305054)
			(stroke
				(width 0.1)
				(type default)
			)
			(layer "B.Fab")
		)
		(fp_line
			(start 0.67945 -0.305054)
			(end 0.12065 -0.305054)
			(stroke
				(width 0.1)
				(type default)
			)
			(layer "B.Fab")
		)
		(fp_line
			(start 0.12065 0.3048)
			(end 0.67945 0.3048)
			(stroke
				(width 0.1)
				(type default)
			)
			(layer "B.Fab")
		)
		(fp_line
			(start 0.12065 0.2794)
			(end 0.12065 0.3048)
			(stroke
				(width 0.1)
				(type default)
			)
			(layer "B.Fab")
		)
		(fp_line
			(start 0.12065 -0.2794)
			(end -0.12065 -0.2794)
			(stroke
				(width 0.1)
				(type default)
			)
			(layer "B.Fab")
		)
		(fp_line
			(start 0.12065 -0.305054)
			(end 0.12065 -0.2794)
			(stroke
				(width 0.1)
				(type default)
			)
			(layer "B.Fab")
		)
		(fp_line
			(start -0.120396 0.3048)
			(end -0.120396 0.2794)
			(stroke
				(width 0.1)
				(type default)
			)
			(layer "B.Fab")
		)
		(fp_line
			(start -0.120396 0.2794)
			(end 0.12065 0.2794)
			(stroke
				(width 0.1)
				(type default)
			)
			(layer "B.Fab")
		)
		(fp_line
			(start -0.12065 -0.2794)
			(end -0.12065 -0.3048)
			(stroke
				(width 0.1)
				(type default)
			)
			(layer "B.Fab")
		)
		(fp_line
			(start -0.12065 -0.3048)
			(end -0.67945 -0.3048)
			(stroke
				(width 0.1)
				(type default)
			)
			(layer "B.Fab")
		)
		(fp_line
			(start -0.67945 0.3048)
			(end -0.120396 0.3048)
			(stroke
				(width 0.1)
				(type default)
			)
			(layer "B.Fab")
		)
		(fp_line
			(start -0.67945 -0.3048)
			(end -0.67945 0.3048)
			(stroke
				(width 0.1)
				(type default)
			)
			(layer "B.Fab")
		)
		(pad "1" smd circle
			(at 0.40005 0)
			(size 0 0)
			(layers "B.Cu" "B.Mask" "B.Paste")
			(net "P1V2_P1V0_I3C_VDDL2")
		)
		(pad "2" smd circle
			(at -0.40005 0)
			(size 0 0)
			(layers "B.Cu" "B.Mask" "B.Paste")
			(net "GND")
		)
	)
	(footprint ""
		(layer "B.Cu")
		(at 33.655 -70.358)
		(property "Reference" "C231"
			(at 0 0 0)
			(layer "B.SilkS")
			(hide yes)
			(effects
				(font
					(size 1.27 1.27)
				)
				(justify mirror)
			)
		)
		(property "Value" ""
			(at 0 0 0)
			(layer "B.Fab")
			(effects
				(font
					(size 1.27 1.27)
				)
				(justify mirror)
			)
		)
		(duplicate_pad_numbers_are_jumpers no)
		(fp_line
			(start -0.7874 -0.4064)
			(end -0.7874 0.4064)
			(stroke
				(width 0.1524)
				(type default)
			)
			(layer "B.SilkS")
		)
		(fp_line
			(start -0.7874 0.4064)
			(end 0.7874 0.4064)
			(stroke
				(width 0.1524)
				(type default)
			)
			(layer "B.SilkS")
		)
		(fp_line
			(start 0.7874 -0.4064)
			(end -0.7874 -0.4064)
			(stroke
				(width 0.1524)
				(type default)
			)
			(layer "B.SilkS")
		)
		(fp_line
			(start 0.7874 0.4064)
			(end 0.7874 -0.4064)
			(stroke
				(width 0.1524)
				(type default)
			)
			(layer "B.SilkS")
		)
		(fp_line
			(start -0.67945 -0.3048)
			(end -0.67945 0.3048)
			(stroke
				(width 0.1)
				(type default)
			)
			(layer "B.Fab")
		)
		(fp_line
			(start -0.67945 0.3048)
			(end -0.120396 0.3048)
			(stroke
				(width 0.1)
				(type default)
			)
			(layer "B.Fab")
		)
		(fp_line
			(start -0.12065 -0.3048)
			(end -0.67945 -0.3048)
			(stroke
				(width 0.1)
				(type default)
			)
			(layer "B.Fab")
		)
		(fp_line
			(start -0.12065 -0.2794)
			(end -0.12065 -0.3048)
			(stroke
				(width 0.1)
				(type default)
			)
			(layer "B.Fab")
		)
		(fp_line
			(start -0.120396 0.2794)
			(end 0.12065 0.2794)
			(stroke
				(width 0.1)
				(type default)
			)
			(layer "B.Fab")
		)
		(fp_line
			(start -0.120396 0.3048)
			(end -0.120396 0.2794)
			(stroke
				(width 0.1)
				(type default)
			)
			(layer "B.Fab")
		)
		(fp_line
			(start 0.12065 -0.305054)
			(end 0.12065 -0.2794)
			(stroke
				(width 0.1)
				(type default)
			)
			(layer "B.Fab")
		)
		(fp_line
			(start 0.12065 -0.2794)
			(end -0.12065 -0.2794)
			(stroke
				(width 0.1)
				(type default)
			)
			(layer "B.Fab")
		)
		(fp_line
			(start 0.12065 0.2794)
			(end 0.12065 0.3048)
			(stroke
				(width 0.1)
				(type default)
			)
			(layer "B.Fab")
		)
		(fp_line
			(start 0.12065 0.3048)
			(end 0.67945 0.3048)
			(stroke
				(width 0.1)
				(type default)
			)
			(layer "B.Fab")
		)
		(fp_line
			(start 0.67945 -0.305054)
			(end 0.12065 -0.305054)
			(stroke
				(width 0.1)
				(type default)
			)
			(layer "B.Fab")
		)
		(fp_line
			(start 0.67945 0.3048)
			(end 0.67945 -0.305054)
			(stroke
				(width 0.1)
				(type default)
			)
			(layer "B.Fab")
		)
		(pad "1" smd circle
			(at 0.40005 0 180)
			(size 0 0)
			(layers "B.Cu" "B.Mask" "B.Paste")
			(net "P3V3_AUX")
		)
		(pad "2" smd circle
			(at -0.40005 0 180)
			(size 0 0)
			(layers "B.Cu" "B.Mask" "B.Paste")
			(net "GND")
		)
	)
)
